FILE_TYPE = CONNECTIVITY;
{Allegro Design Entry HDL 17.2-2016 S066 (3851973) 4/6/2020}
"PAGE_NUMBER" = 528;
0"NC";
END.
